(kicad_pcb
	(version 20260206)
	(generator "pcbnew")
	(generator_version "10.0")
	(general
		(thickness 1.6)
		(legacy_teardrops no)
	)
	(paper "A4")
	(title_block
		(title "4HDD Backplane_Layout.brd")
		(comment 1 "Tioga Pass / footprints 71-71 of 97")
	)
	(layers
		(0 "F.Cu" signal "TOP")
		(4 "In1.Cu" signal "L2GND")
		(6 "In2.Cu" signal "L3")
		(8 "In3.Cu" signal "L4")
		(10 "In4.Cu" signal "L5GND")
		(2 "B.Cu" signal "BOTTOM")
		(9 "F.Adhes" user "F.Adhesive")
		(11 "B.Adhes" user "B.Adhesive")
		(13 "F.Paste" user "Package Geometry/Pastemask Top")
		(15 "B.Paste" user "Package Geometry/Pastemask Bottom")
		(5 "F.SilkS" user "Ref Des/Silkscreen Top")
		(7 "B.SilkS" user "Ref Des/Silkscreen Bottom")
		(1 "F.Mask" user "Board Geometry/Soldermask Top")
		(3 "B.Mask" user "Board Geometry/Soldermask Bottom")
		(17 "Dwgs.User" user "User.Drawings")
		(19 "Cmts.User" user "User.Comments")
		(21 "Eco1.User" user "User.Eco1")
		(23 "Eco2.User" user "User.Eco2")
		(25 "Edge.Cuts" user "Board Geometry/Outline")
		(27 "Margin" user)
		(31 "F.CrtYd" user "Package Geometry/Place Bound Top")
		(29 "B.CrtYd" user "Package Geometry/Place Bound Bottom")
		(35 "F.Fab" user "Ref Des/Assembly Top")
		(33 "B.Fab" user "Ref Des/Assembly Bottom")
	)
	(footprint ""
		(layer "B.Cu")
		(at 79.414878 -22.079966 -90)
		(property "Reference" "MISAS1"
			(at 0 0 90)
			(layer "B.SilkS")
			(hide yes)
			(effects
				(font
					(size 1.27 1.27)
				)
				(justify mirror)
			)
		)
		(property "Value" "AMP-CONN36-4R-1-GP"
			(at 7.3279 -6.5278 270)
			(unlocked yes)
			(layer "B.Fab")
			(hide yes)
			(effects
				(font
					(size 1.016 1.016)
					(thickness 0.1524)
				)
				(justify mirror)
			)
		)
		(property "Device Type" "G40H2132212HR-W"
			(at 7.3279 -8.0518 270)
			(unlocked yes)
			(layer "B.Fab")
			(hide yes)
			(effects
				(font
					(size 1.016 1.016)
					(thickness 0.1524)
				)
				(justify mirror)
			)
		)
		(duplicate_pad_numbers_are_jumpers no)
		(fp_line
			(start 3.2512 6.2611)
			(end 2.794 6.2611)
			(stroke
				(width 0.3302)
				(type default)
			)
			(layer "B.SilkS")
		)
		(fp_line
			(start -6.3373 6.1722)
			(end 6.3373 6.1722)
			(stroke
				(width 0.1524)
				(type default)
			)
			(layer "B.SilkS")
		)
		(fp_line
			(start 6.3373 6.1722)
			(end 6.3373 -8.255)
			(stroke
				(width 0.1524)
				(type default)
			)
			(layer "B.SilkS")
		)
		(fp_line
			(start -4.459732 4.84759)
			(end -4.459732 3.88239)
			(stroke
				(width 0.3048)
				(type default)
			)
			(layer "B.SilkS")
		)
		(fp_line
			(start 6.390132 4.84759)
			(end 6.390132 3.88239)
			(stroke
				(width 0.3048)
				(type default)
			)
			(layer "B.SilkS")
		)
		(fp_line
			(start -6.390132 3.88239)
			(end -6.390132 4.84759)
			(stroke
				(width 0.3048)
				(type default)
			)
			(layer "B.SilkS")
		)
		(fp_line
			(start 4.459732 3.88239)
			(end 4.459732 4.84759)
			(stroke
				(width 0.3048)
				(type default)
			)
			(layer "B.SilkS")
		)
		(fp_line
			(start -4.459732 -4.072382)
			(end -4.459732 -5.037582)
			(stroke
				(width 0.3048)
				(type default)
			)
			(layer "B.SilkS")
		)
		(fp_line
			(start 6.390132 -4.072382)
			(end 6.390132 -5.037582)
			(stroke
				(width 0.3048)
				(type default)
			)
			(layer "B.SilkS")
		)
		(fp_line
			(start -6.390132 -5.037582)
			(end -6.390132 -4.072382)
			(stroke
				(width 0.3048)
				(type default)
			)
			(layer "B.SilkS")
		)
		(fp_line
			(start 4.459732 -5.037582)
			(end 4.459732 -4.072382)
			(stroke
				(width 0.3048)
				(type default)
			)
			(layer "B.SilkS")
		)
		(fp_line
			(start -6.3373 -8.255)
			(end -6.3373 6.1722)
			(stroke
				(width 0.1524)
				(type default)
			)
			(layer "B.SilkS")
		)
		(fp_line
			(start -3.3782 -8.255)
			(end -6.3373 -8.255)
			(stroke
				(width 0.1524)
				(type default)
			)
			(layer "B.SilkS")
		)
		(fp_line
			(start 3.3782 -8.255)
			(end 3.3782 -8.509)
			(stroke
				(width 0.1524)
				(type default)
			)
			(layer "B.SilkS")
		)
		(fp_line
			(start 6.3373 -8.255)
			(end 3.3782 -8.255)
			(stroke
				(width 0.1524)
				(type default)
			)
			(layer "B.SilkS")
		)
		(fp_line
			(start -3.3782 -8.509)
			(end -3.3782 -8.255)
			(stroke
				(width 0.1524)
				(type default)
			)
			(layer "B.SilkS")
		)
		(fp_line
			(start 3.3782 -8.509)
			(end -3.3782 -8.509)
			(stroke
				(width 0.1524)
				(type default)
			)
			(layer "B.SilkS")
		)
		(fp_arc
			(start -4.459732 4.84759)
			(mid -5.424934 5.81278)
			(end -6.390132 4.84759)
			(stroke
				(width 0.3048)
				(type default)
			)
			(layer "B.SilkS")
		)
		(fp_arc
			(start 6.390132 4.84759)
			(mid 5.424966 5.812744)
			(end 4.459732 4.84759)
			(stroke
				(width 0.3048)
				(type default)
			)
			(layer "B.SilkS")
		)
		(fp_arc
			(start -6.390132 3.88239)
			(mid -5.424934 2.91718)
			(end -4.459732 3.88239)
			(stroke
				(width 0.3048)
				(type default)
			)
			(layer "B.SilkS")
		)
		(fp_arc
			(start 4.459732 3.88239)
			(mid 5.424966 2.917144)
			(end 6.390132 3.88239)
			(stroke
				(width 0.3048)
				(type default)
			)
			(layer "B.SilkS")
		)
		(fp_arc
			(start -4.459732 -4.072382)
			(mid -5.424934 -3.10722)
			(end -6.390132 -4.072382)
			(stroke
				(width 0.3048)
				(type default)
			)
			(layer "B.SilkS")
		)
		(fp_arc
			(start 6.390132 -4.072382)
			(mid 5.424966 -3.107256)
			(end 4.459732 -4.072382)
			(stroke
				(width 0.3048)
				(type default)
			)
			(layer "B.SilkS")
		)
		(fp_arc
			(start -6.390132 -5.037582)
			(mid -5.424934 -6.00282)
			(end -4.459732 -5.037582)
			(stroke
				(width 0.3048)
				(type default)
			)
			(layer "B.SilkS")
		)
		(fp_arc
			(start 4.459732 -5.037582)
			(mid 5.424966 -6.002856)
			(end 6.390132 -5.037582)
			(stroke
				(width 0.3048)
				(type default)
			)
			(layer "B.SilkS")
		)
		(fp_poly
			(pts
				(xy 3.002026 6.23951) (xy 3.637026 6.87451) (xy 2.367026 6.87451)
			)
			(stroke
				(width 0)
				(type default)
			)
			(fill yes)
			(layer "B.SilkS")
		)
		(fp_poly
			(pts
				(xy 3.177794 1.930146) (xy 3.177794 3.029966) (xy -3.177794 3.029966) (xy -3.177794 1.930146)
			)
			(stroke
				(width 0)
				(type default)
			)
			(fill yes)
			(layer "B.SilkS")
		)
		(fp_poly
			(pts
				(xy 3.177794 -1.599946) (xy 3.177794 0.329946) (xy -3.177794 0.329946) (xy -3.177794 -1.599946)
			)
			(stroke
				(width 0)
				(type default)
			)
			(fill yes)
			(layer "B.SilkS")
		)
		(fp_poly
			(pts
				(xy 3.177794 -4.299966) (xy 3.177794 -3.200146) (xy -3.177794 -3.200146) (xy -3.177794 -4.299966)
			)
			(stroke
				(width 0)
				(type default)
			)
			(fill yes)
			(layer "B.SilkS")
		)
		(fp_poly
			(pts
				(xy 6.0833 5.9182) (xy 6.0833 -8.001) (xy 3.1242 -8.001) (xy 3.1242 -8.255) (xy -3.1242 -8.255)
				(xy -3.1242 -8.001) (xy -6.0833 -8.001) (xy -6.0833 5.9182)
			)
			(stroke
				(width 0)
				(type default)
			)
			(fill no)
			(layer "B.CrtYd")
		)
		(fp_poly
			(pts
				(xy 6.5913 6.4262) (xy 6.5913 -8.509) (xy 3.6322 -8.509) (xy 3.6322 -8.763) (xy -3.6322 -8.763)
				(xy -3.6322 -8.509) (xy -6.5913 -8.509) (xy -6.5913 -0.00635) (xy -6.0833 -0.00635) (xy -6.0833 -8.001)
				(xy -3.1242 -8.001) (xy -3.1242 -8.255) (xy 3.1242 -8.255) (xy 3.1242 -8.001) (xy 6.0833 -8.001)
				(xy 6.0833 5.9182) (xy -6.0833 5.9182) (xy -6.0833 0.00635) (xy -6.5913 0.00635) (xy -6.5913 6.4262)
			)
			(stroke
				(width 0)
				(type default)
			)
			(fill no)
			(layer "B.CrtYd")
		)
		(fp_poly
			(pts
				(xy 6.5913 6.4262) (xy 6.5913 -8.509) (xy 3.6322 -8.509) (xy 3.6322 -8.763) (xy -3.6322 -8.763)
				(xy -3.6322 -8.509) (xy -6.5913 -8.509) (xy -6.5913 6.4262)
			)
			(stroke
				(width 0)
				(type default)
			)
			(fill no)
			(layer "B.Fab")
		)
		(pad "" np_thru_hole circle
			(at -5.279898 0 90)
			(size 0.254 0.254)
			(drill 1.2192)
			(layers "*.Cu" "*.Mask")
			(clearance 0.8382)
			(thermal_gap 0.8382)
		)
		(pad "" np_thru_hole circle
			(at 5.279898 0 90)
			(size 0.254 0.254)
			(drill 1.2192)
			(layers "*.Cu" "*.Mask")
			(clearance 0.8382)
			(thermal_gap 0.8382)
		)
		(pad "37" thru_hole oval
			(at 5.424932 -4.554982 90)
			(size 1.2192 2.1844)
			(drill oval 0.508 1.4732)
			(layers "*.Cu" "*.Mask")
			(remove_unused_layers no)
			(net "Net_116")
			(clearance 0.1524)
			(thermal_gap 0.1524)
		)
		(pad "38" thru_hole oval
			(at 5.424932 4.36499 90)
			(size 1.2192 2.1844)
			(drill oval 0.508 1.4732)
			(layers "*.Cu" "*.Mask")
			(remove_unused_layers no)
			(net "Net_118")
			(clearance 0.1524)
			(thermal_gap 0.1524)
		)
		(pad "39" thru_hole oval
			(at -5.424932 -4.554982 90)
			(size 1.2192 2.1844)
			(drill oval 0.508 1.4732)
			(layers "*.Cu" "*.Mask")
			(remove_unused_layers no)
			(net "Net_105")
			(clearance 0.1524)
			(thermal_gap 0.1524)
		)
		(pad "40" thru_hole oval
			(at -5.424932 4.36499 90)
			(size 1.2192 2.1844)
			(drill oval 0.508 1.4732)
			(layers "*.Cu" "*.Mask")
			(remove_unused_layers no)
			(net "Net_107")
			(clearance 0.1524)
			(thermal_gap 0.1524)
		)
		(pad "A1" smd rect
			(at 2.999994 3.830066 90)
			(size 0.3556 1.1938)
			(layers "B.Cu" "B.Mask" "B.Paste")
			(net "Net_114")
		)
		(pad "A2" smd rect
			(at 2.249932 3.830066 90)
			(size 0.3556 1.1938)
			(layers "B.Cu" "B.Mask" "B.Paste")
			(net "Net_115")
		)
		(pad "A3" smd rect
			(at 1.500124 3.830066 90)
			(size 0.3556 1.1938)
			(layers "B.Cu" "B.Mask" "B.Paste")
			(net "GND")
		)
		(pad "A4" smd rect
			(at 0.750062 3.830066 90)
			(size 0.3556 1.1938)
			(layers "B.Cu" "B.Mask" "B.Paste")
			(net "HBA_MB_RX_P1")
		)
		(pad "A5" smd rect
			(at 0 3.830066 90)
			(size 0.3556 1.1938)
			(layers "B.Cu" "B.Mask" "B.Paste")
			(net "HBA_MB_RX_N1")
		)
		(pad "A6" smd rect
			(at -0.750062 3.830066 90)
			(size 0.3556 1.1938)
			(layers "B.Cu" "B.Mask" "B.Paste")
			(net "GND")
		)
		(pad "A7" smd rect
			(at -1.500124 3.830066 90)
			(size 0.3556 1.1938)
			(layers "B.Cu" "B.Mask" "B.Paste")
			(net "HBA_MB_RX_P3")
		)
		(pad "A8" smd rect
			(at -2.249932 3.830066 90)
			(size 0.3556 1.1938)
			(layers "B.Cu" "B.Mask" "B.Paste")
			(net "HBA_MB_RX_N3")
		)
		(pad "A9" smd rect
			(at -2.999994 3.830066 90)
			(size 0.3556 1.1938)
			(layers "B.Cu" "B.Mask" "B.Paste")
			(net "GND")
		)
		(pad "B1" smd rect
			(at 2.999994 1.130046 90)
			(size 0.3556 1.1938)
			(layers "B.Cu" "B.Mask" "B.Paste")
			(net "Net_112")
		)
		(pad "B2" smd rect
			(at 2.249932 1.130046 90)
			(size 0.3556 1.1938)
			(layers "B.Cu" "B.Mask" "B.Paste")
			(net "Net_113")
		)
		(pad "B3" smd rect
			(at 1.500124 1.130046 90)
			(size 0.3556 1.1938)
			(layers "B.Cu" "B.Mask" "B.Paste")
			(net "GND")
		)
		(pad "B4" smd rect
			(at 0.750062 1.130046 90)
			(size 0.3556 1.1938)
			(layers "B.Cu" "B.Mask" "B.Paste")
			(net "HBA_MB_RX_P0")
		)
		(pad "B5" smd rect
			(at 0 1.130046 90)
			(size 0.3556 1.1938)
			(layers "B.Cu" "B.Mask" "B.Paste")
			(net "HBA_MB_RX_N0")
		)
		(pad "B6" smd rect
			(at -0.750062 1.130046 90)
			(size 0.3556 1.1938)
			(layers "B.Cu" "B.Mask" "B.Paste")
			(net "GND")
		)
		(pad "B7" smd rect
			(at -1.500124 1.130046 90)
			(size 0.3556 1.1938)
			(layers "B.Cu" "B.Mask" "B.Paste")
			(net "HBA_MB_RX_P2")
		)
		(pad "B8" smd rect
			(at -2.249932 1.130046 90)
			(size 0.3556 1.1938)
			(layers "B.Cu" "B.Mask" "B.Paste")
			(net "HBA_MB_RX_N2")
		)
		(pad "B9" smd rect
			(at -2.999994 1.130046 90)
			(size 0.3556 1.1938)
			(layers "B.Cu" "B.Mask" "B.Paste")
			(net "GND")
		)
		(pad "C1" smd rect
			(at 2.999994 -2.400046 90)
			(size 0.3556 1.1938)
			(layers "B.Cu" "B.Mask" "B.Paste")
			(net "Net_108")
		)
		(pad "C2" smd rect
			(at 2.249932 -2.400046 90)
			(size 0.3556 1.1938)
			(layers "B.Cu" "B.Mask" "B.Paste")
			(net "Net_109")
		)
		(pad "C3" smd rect
			(at 1.500124 -2.400046 90)
			(size 0.3556 1.1938)
			(layers "B.Cu" "B.Mask" "B.Paste")
			(net "GND")
		)
		(pad "C4" smd rect
			(at 0.750062 -2.400046 90)
			(size 0.3556 1.1938)
			(layers "B.Cu" "B.Mask" "B.Paste")
			(net "HBA_MB_TX_P1")
		)
		(pad "C5" smd rect
			(at 0 -2.400046 90)
			(size 0.3556 1.1938)
			(layers "B.Cu" "B.Mask" "B.Paste")
			(net "HBA_MB_TX_N1")
		)
		(pad "C6" smd rect
			(at -0.750062 -2.400046 90)
			(size 0.3556 1.1938)
			(layers "B.Cu" "B.Mask" "B.Paste")
			(net "GND")
		)
		(pad "C7" smd rect
			(at -1.500124 -2.400046 90)
			(size 0.3556 1.1938)
			(layers "B.Cu" "B.Mask" "B.Paste")
			(net "HBA_MB_TX_P3")
		)
		(pad "C8" smd rect
			(at -2.249932 -2.400046 90)
			(size 0.3556 1.1938)
			(layers "B.Cu" "B.Mask" "B.Paste")
			(net "HBA_MB_TX_N3")
		)
		(pad "C9" smd rect
			(at -2.999994 -2.400046 90)
			(size 0.3556 1.1938)
			(layers "B.Cu" "B.Mask" "B.Paste")
			(net "GND")
		)
		(pad "D1" smd rect
			(at 2.999994 -5.100066 90)
			(size 0.3556 1.1938)
			(layers "B.Cu" "B.Mask" "B.Paste")
			(net "Net_110")
		)
		(pad "D2" smd rect
			(at 2.249932 -5.100066 90)
			(size 0.3556 1.1938)
			(layers "B.Cu" "B.Mask" "B.Paste")
			(net "Net_111")
		)
		(pad "D3" smd rect
			(at 1.500124 -5.100066 90)
			(size 0.3556 1.1938)
			(layers "B.Cu" "B.Mask" "B.Paste")
			(net "GND")
		)
		(pad "D4" smd rect
			(at 0.750062 -5.100066 90)
			(size 0.3556 1.1938)
			(layers "B.Cu" "B.Mask" "B.Paste")
			(net "HBA_MB_TX_P0")
		)
		(pad "D5" smd rect
			(at 0 -5.100066 90)
			(size 0.3556 1.1938)
			(layers "B.Cu" "B.Mask" "B.Paste")
			(net "HBA_MB_TX_N0")
		)
		(pad "D6" smd rect
			(at -0.750062 -5.100066 90)
			(size 0.3556 1.1938)
			(layers "B.Cu" "B.Mask" "B.Paste")
			(net "GND")
		)
		(pad "D7" smd rect
			(at -1.500124 -5.100066 90)
			(size 0.3556 1.1938)
			(layers "B.Cu" "B.Mask" "B.Paste")
			(net "HBA_MB_TX_P2")
		)
		(pad "D8" smd rect
			(at -2.249932 -5.100066 90)
			(size 0.3556 1.1938)
			(layers "B.Cu" "B.Mask" "B.Paste")
			(net "HBA_MB_TX_N2")
		)
		(pad "D9" smd rect
			(at -2.999994 -5.100066 90)
			(size 0.3556 1.1938)
			(layers "B.Cu" "B.Mask" "B.Paste")
			(net "GND")
		)
		(zone
			(layers "F.Cu" "B.Cu" "In1.Cu" "In2.Cu" "In3.Cu" "In4.Cu")
			(hatch none 0.5)
			(connect_pads
				(clearance 0)
			)
			(min_thickness 0.25)
			(keepout
				(tracks not_allowed)
				(vias allowed)
				(pads allowed)
				(copperpour not_allowed)
				(footprints allowed)
			)
			(placement
				(enabled no)
				(sheetname "")
			)
			(fill
				(thermal_gap 0.5)
				(thermal_bridge_width 0.5)
				(island_removal_mode 0)
			)
			(polygon
				(pts
					(arc
						(start 80.329278 -27.359864)
						(mid 78.500478 -27.359864)
						(end 80.329278 -27.359864)
					)
				)
			)
		)
		(zone
			(layers "F.Cu" "B.Cu" "In1.Cu" "In2.Cu" "In3.Cu" "In4.Cu")
			(hatch none 0.5)
			(connect_pads
				(clearance 0)
			)
			(min_thickness 0.25)
			(keepout
				(tracks not_allowed)
				(vias allowed)
				(pads allowed)
				(copperpour not_allowed)
				(footprints allowed)
			)
			(placement
				(enabled no)
				(sheetname "")
			)
			(fill
				(thermal_gap 0.5)
				(thermal_bridge_width 0.5)
				(island_removal_mode 0)
			)
			(polygon
				(pts
					(arc
						(start 80.329278 -16.800068)
						(mid 78.500478 -16.800068)
						(end 80.329278 -16.800068)
					)
				)
			)
		)
		(zone
			(layer "B.Cu")
			(hatch none 0.5)
			(connect_pads
				(clearance 0)
			)
			(min_thickness 0.25)
			(keepout
				(tracks allowed)
				(vias not_allowed)
				(pads allowed)
				(copperpour not_allowed)
				(footprints allowed)
			)
			(placement
				(enabled no)
				(sheetname "")
			)
			(fill
				(thermal_gap 0.5)
				(thermal_bridge_width 0.5)
				(island_removal_mode 0)
			)
			(polygon
				(pts
					(xy 76.689712 -18.902172) (xy 76.181712 -18.902172) (xy 76.181712 -25.25776) (xy 76.689712 -25.25776)
				)
			)
		)
		(zone
			(layer "B.Cu")
			(hatch none 0.5)
			(connect_pads
				(clearance 0)
			)
			(min_thickness 0.25)
			(keepout
				(tracks allowed)
				(vias not_allowed)
				(pads allowed)
				(copperpour not_allowed)
				(footprints allowed)
			)
			(placement
				(enabled no)
				(sheetname "")
			)
			(fill
				(thermal_gap 0.5)
				(thermal_bridge_width 0.5)
				(island_removal_mode 0)
			)
			(polygon
				(pts
					(xy 79.389732 -18.902172) (xy 78.881732 -18.902172) (xy 78.881732 -25.25776) (xy 79.389732 -25.25776)
				)
			)
		)
		(zone
			(layer "B.Cu")
			(hatch none 0.5)
			(connect_pads
				(clearance 0)
			)
			(min_thickness 0.25)
			(keepout
				(tracks allowed)
				(vias not_allowed)
				(pads allowed)
				(copperpour not_allowed)
				(footprints allowed)
			)
			(placement
				(enabled no)
				(sheetname "")
			)
			(fill
				(thermal_gap 0.5)
				(thermal_bridge_width 0.5)
				(island_removal_mode 0)
			)
			(polygon
				(pts
					(xy 81.218024 -18.902172) (xy 80.710024 -18.902172) (xy 80.710024 -25.25776) (xy 81.218024 -25.25776)
				)
			)
		)
		(zone
			(layer "B.Cu")
			(hatch none 0.5)
			(connect_pads
				(clearance 0)
			)
			(min_thickness 0.25)
			(keepout
				(tracks allowed)
				(vias not_allowed)
				(pads allowed)
				(copperpour not_allowed)
				(footprints allowed)
			)
			(placement
				(enabled no)
				(sheetname "")
			)
			(fill
				(thermal_gap 0.5)
				(thermal_bridge_width 0.5)
				(island_removal_mode 0)
			)
			(polygon
				(pts
					(xy 83.918044 -18.902172) (xy 83.410044 -18.902172) (xy 83.410044 -25.25776) (xy 83.918044 -25.25776)
				)
			)
		)
	)
)
